(kicad_pcb
	(version 20260206)
	(generator "pcbnew")
	(generator_version "10.0")
	(general
		(thickness 1.6)
		(legacy_teardrops no)
	)
	(paper "A4")
	(title_block
		(title "03242023_DA0F0TMBIJ0_F0T_Motherboard_J_brd_V01_OCP.brd")
		(comment 1 "Grand Teton / footprints 1628-1634 of 6105")
	)
	(layers
		(0 "F.Cu" signal "TOP")
		(4 "In1.Cu" signal "GND")
		(6 "In2.Cu" signal "IN1")
		(8 "In3.Cu" signal "GND1")
		(10 "In4.Cu" signal "IN2")
		(12 "In5.Cu" signal "GND2")
		(14 "In6.Cu" signal "IN3")
		(16 "In7.Cu" signal "GND3")
		(18 "In8.Cu" signal "VCC")
		(20 "In9.Cu" signal "VCC1")
		(22 "In10.Cu" signal "GND4")
		(24 "In11.Cu" signal "IN4")
		(26 "In12.Cu" signal "GND5")
		(28 "In13.Cu" signal "IN5")
		(30 "In14.Cu" signal "GND6")
		(32 "In15.Cu" signal "IN6")
		(34 "In16.Cu" signal "GND7")
		(2 "B.Cu" signal "BOTTOM")
		(9 "F.Adhes" user "F.Adhesive")
		(11 "B.Adhes" user "B.Adhesive")
		(13 "F.Paste" user "Package Geometry/Pastemask Top")
		(15 "B.Paste" user "Package Geometry/Pastemask Bottom")
		(5 "F.SilkS" user "Ref Des/Silkscreen Top")
		(7 "B.SilkS" user "Ref Des/Silkscreen Bottom")
		(1 "F.Mask" user "Board Geometry/Soldermask Top")
		(3 "B.Mask" user "Board Geometry/Soldermask Bottom")
		(17 "Dwgs.User" user "User.Drawings")
		(19 "Cmts.User" user "User.Comments")
		(21 "Eco1.User" user "User.Eco1")
		(23 "Eco2.User" user "User.Eco2")
		(25 "Edge.Cuts" user "Board Geometry/Outline")
		(27 "Margin" user)
		(31 "F.CrtYd" user "Package Geometry/Place Bound Top")
		(29 "B.CrtYd" user "Package Geometry/Place Bound Bottom")
		(35 "F.Fab" user "Ref Des/Assembly Top")
		(33 "B.Fab" user "Ref Des/Assembly Bottom")
	)
	(footprint ""
		(layer "F.Cu")
		(at 9.652 -48.986948)
		(property "Reference" "R3053"
			(at 0 0 0)
			(layer "F.SilkS")
			(hide yes)
			(effects
				(font
					(size 1.27 1.27)
				)
			)
		)
		(property "Value" ""
			(at 0 0 0)
			(layer "F.Fab")
			(effects
				(font
					(size 1.27 1.27)
				)
			)
		)
		(duplicate_pad_numbers_are_jumpers no)
		(fp_line
			(start -0.7874 -0.4064)
			(end 0.7874 -0.4064)
			(stroke
				(width 0.1524)
				(type default)
			)
			(layer "F.SilkS")
		)
		(fp_line
			(start -0.7874 0.4064)
			(end -0.7874 -0.4064)
			(stroke
				(width 0.1524)
				(type default)
			)
			(layer "F.SilkS")
		)
		(fp_line
			(start 0.7874 -0.4064)
			(end 0.7874 0.4064)
			(stroke
				(width 0.1524)
				(type default)
			)
			(layer "F.SilkS")
		)
		(fp_line
			(start 0.7874 0.4064)
			(end -0.7874 0.4064)
			(stroke
				(width 0.1524)
				(type default)
			)
			(layer "F.SilkS")
		)
		(fp_line
			(start -0.67945 -0.305054)
			(end -0.12065 -0.305054)
			(stroke
				(width 0.1)
				(type default)
			)
			(layer "F.Fab")
		)
		(fp_line
			(start -0.67945 0.3048)
			(end -0.67945 -0.305054)
			(stroke
				(width 0.1)
				(type default)
			)
			(layer "F.Fab")
		)
		(fp_line
			(start -0.12065 -0.305054)
			(end -0.12065 -0.2794)
			(stroke
				(width 0.1)
				(type default)
			)
			(layer "F.Fab")
		)
		(fp_line
			(start -0.12065 -0.2794)
			(end 0.12065 -0.2794)
			(stroke
				(width 0.1)
				(type default)
			)
			(layer "F.Fab")
		)
		(fp_line
			(start -0.12065 0.2794)
			(end -0.12065 0.3048)
			(stroke
				(width 0.1)
				(type default)
			)
			(layer "F.Fab")
		)
		(fp_line
			(start -0.12065 0.3048)
			(end -0.67945 0.3048)
			(stroke
				(width 0.1)
				(type default)
			)
			(layer "F.Fab")
		)
		(fp_line
			(start 0.120396 0.2794)
			(end -0.12065 0.2794)
			(stroke
				(width 0.1)
				(type default)
			)
			(layer "F.Fab")
		)
		(fp_line
			(start 0.120396 0.3048)
			(end 0.120396 0.2794)
			(stroke
				(width 0.1)
				(type default)
			)
			(layer "F.Fab")
		)
		(fp_line
			(start 0.12065 -0.3048)
			(end 0.67945 -0.3048)
			(stroke
				(width 0.1)
				(type default)
			)
			(layer "F.Fab")
		)
		(fp_line
			(start 0.12065 -0.2794)
			(end 0.12065 -0.3048)
			(stroke
				(width 0.1)
				(type default)
			)
			(layer "F.Fab")
		)
		(fp_line
			(start 0.67945 -0.3048)
			(end 0.67945 0.3048)
			(stroke
				(width 0.1)
				(type default)
			)
			(layer "F.Fab")
		)
		(fp_line
			(start 0.67945 0.3048)
			(end 0.120396 0.3048)
			(stroke
				(width 0.1)
				(type default)
			)
			(layer "F.Fab")
		)
		(pad "1" smd circle
			(at -0.40005 0)
			(size 0 0)
			(layers "F.Cu" "F.Mask" "F.Paste")
			(net "SMB_HOST_3V3AUX_SDA_R5")
		)
		(pad "2" smd circle
			(at 0.40005 0)
			(size 0 0)
			(layers "F.Cu" "F.Mask" "F.Paste")
			(net "SMB_HOST_ME_SDA")
		)
	)
	(footprint ""
		(layer "F.Cu")
		(at 156.37129 -81.90357 -90)
		(property "Reference" "R3222"
			(at 0 0 270)
			(layer "F.SilkS")
			(hide yes)
			(effects
				(font
					(size 1.27 1.27)
				)
			)
		)
		(property "Value" ""
			(at 0 0 270)
			(layer "F.Fab")
			(effects
				(font
					(size 1.27 1.27)
				)
			)
		)
		(duplicate_pad_numbers_are_jumpers no)
		(fp_line
			(start -0.7874 0.4064)
			(end -0.7874 -0.4064)
			(stroke
				(width 0.1524)
				(type default)
			)
			(layer "F.SilkS")
		)
		(fp_line
			(start 0.7874 0.4064)
			(end -0.7874 0.4064)
			(stroke
				(width 0.1524)
				(type default)
			)
			(layer "F.SilkS")
		)
		(fp_line
			(start -0.7874 -0.4064)
			(end 0.7874 -0.4064)
			(stroke
				(width 0.1524)
				(type default)
			)
			(layer "F.SilkS")
		)
		(fp_line
			(start 0.7874 -0.4064)
			(end 0.7874 0.4064)
			(stroke
				(width 0.1524)
				(type default)
			)
			(layer "F.SilkS")
		)
		(fp_line
			(start -0.67945 0.3048)
			(end -0.67945 -0.305054)
			(stroke
				(width 0.1)
				(type default)
			)
			(layer "F.Fab")
		)
		(fp_line
			(start -0.12065 0.3048)
			(end -0.67945 0.3048)
			(stroke
				(width 0.1)
				(type default)
			)
			(layer "F.Fab")
		)
		(fp_line
			(start 0.120396 0.3048)
			(end 0.120396 0.2794)
			(stroke
				(width 0.1)
				(type default)
			)
			(layer "F.Fab")
		)
		(fp_line
			(start 0.67945 0.3048)
			(end 0.120396 0.3048)
			(stroke
				(width 0.1)
				(type default)
			)
			(layer "F.Fab")
		)
		(fp_line
			(start -0.12065 0.2794)
			(end -0.12065 0.3048)
			(stroke
				(width 0.1)
				(type default)
			)
			(layer "F.Fab")
		)
		(fp_line
			(start 0.120396 0.2794)
			(end -0.12065 0.2794)
			(stroke
				(width 0.1)
				(type default)
			)
			(layer "F.Fab")
		)
		(fp_line
			(start -0.12065 -0.2794)
			(end 0.12065 -0.2794)
			(stroke
				(width 0.1)
				(type default)
			)
			(layer "F.Fab")
		)
		(fp_line
			(start 0.12065 -0.2794)
			(end 0.12065 -0.3048)
			(stroke
				(width 0.1)
				(type default)
			)
			(layer "F.Fab")
		)
		(fp_line
			(start 0.12065 -0.3048)
			(end 0.67945 -0.3048)
			(stroke
				(width 0.1)
				(type default)
			)
			(layer "F.Fab")
		)
		(fp_line
			(start 0.67945 -0.3048)
			(end 0.67945 0.3048)
			(stroke
				(width 0.1)
				(type default)
			)
			(layer "F.Fab")
		)
		(fp_line
			(start -0.67945 -0.305054)
			(end -0.12065 -0.305054)
			(stroke
				(width 0.1)
				(type default)
			)
			(layer "F.Fab")
		)
		(fp_line
			(start -0.12065 -0.305054)
			(end -0.12065 -0.2794)
			(stroke
				(width 0.1)
				(type default)
			)
			(layer "F.Fab")
		)
		(pad "1" smd circle
			(at -0.40005 0 270)
			(size 0 0)
			(layers "F.Cu" "F.Mask" "F.Paste")
			(net "SMB_S3M_CPU0_PIROM_3V3AUX_SCL")
		)
		(pad "2" smd circle
			(at 0.40005 0 270)
			(size 0 0)
			(layers "F.Cu" "F.Mask" "F.Paste")
			(net "P3V3_AUX")
		)
	)
	(footprint ""
		(layer "F.Cu")
		(at 136.07288 -92.674948 90)
		(property "Reference" "R4406"
			(at 0 0 90)
			(layer "F.SilkS")
			(hide yes)
			(effects
				(font
					(size 1.27 1.27)
				)
			)
		)
		(property "Value" ""
			(at 0 0 90)
			(layer "F.Fab")
			(effects
				(font
					(size 1.27 1.27)
				)
			)
		)
		(duplicate_pad_numbers_are_jumpers no)
		(fp_line
			(start 0.7874 -0.4064)
			(end 0.7874 0.4064)
			(stroke
				(width 0.1524)
				(type default)
			)
			(layer "F.SilkS")
		)
		(fp_line
			(start -0.7874 -0.4064)
			(end 0.7874 -0.4064)
			(stroke
				(width 0.1524)
				(type default)
			)
			(layer "F.SilkS")
		)
		(fp_line
			(start 0.7874 0.4064)
			(end -0.7874 0.4064)
			(stroke
				(width 0.1524)
				(type default)
			)
			(layer "F.SilkS")
		)
		(fp_line
			(start -0.7874 0.4064)
			(end -0.7874 -0.4064)
			(stroke
				(width 0.1524)
				(type default)
			)
			(layer "F.SilkS")
		)
		(fp_line
			(start -0.12065 -0.305054)
			(end -0.12065 -0.2794)
			(stroke
				(width 0.1)
				(type default)
			)
			(layer "F.Fab")
		)
		(fp_line
			(start -0.67945 -0.305054)
			(end -0.12065 -0.305054)
			(stroke
				(width 0.1)
				(type default)
			)
			(layer "F.Fab")
		)
		(fp_line
			(start 0.67945 -0.3048)
			(end 0.67945 0.3048)
			(stroke
				(width 0.1)
				(type default)
			)
			(layer "F.Fab")
		)
		(fp_line
			(start 0.12065 -0.3048)
			(end 0.67945 -0.3048)
			(stroke
				(width 0.1)
				(type default)
			)
			(layer "F.Fab")
		)
		(fp_line
			(start 0.12065 -0.2794)
			(end 0.12065 -0.3048)
			(stroke
				(width 0.1)
				(type default)
			)
			(layer "F.Fab")
		)
		(fp_line
			(start -0.12065 -0.2794)
			(end 0.12065 -0.2794)
			(stroke
				(width 0.1)
				(type default)
			)
			(layer "F.Fab")
		)
		(fp_line
			(start 0.120396 0.2794)
			(end -0.12065 0.2794)
			(stroke
				(width 0.1)
				(type default)
			)
			(layer "F.Fab")
		)
		(fp_line
			(start -0.12065 0.2794)
			(end -0.12065 0.3048)
			(stroke
				(width 0.1)
				(type default)
			)
			(layer "F.Fab")
		)
		(fp_line
			(start 0.67945 0.3048)
			(end 0.120396 0.3048)
			(stroke
				(width 0.1)
				(type default)
			)
			(layer "F.Fab")
		)
		(fp_line
			(start 0.120396 0.3048)
			(end 0.120396 0.2794)
			(stroke
				(width 0.1)
				(type default)
			)
			(layer "F.Fab")
		)
		(fp_line
			(start -0.12065 0.3048)
			(end -0.67945 0.3048)
			(stroke
				(width 0.1)
				(type default)
			)
			(layer "F.Fab")
		)
		(fp_line
			(start -0.67945 0.3048)
			(end -0.67945 -0.305054)
			(stroke
				(width 0.1)
				(type default)
			)
			(layer "F.Fab")
		)
		(pad "1" smd circle
			(at -0.40005 0 90)
			(size 0 0)
			(layers "F.Cu" "F.Mask" "F.Paste")
			(net "P3V3")
		)
		(pad "2" smd circle
			(at 0.40005 0 90)
			(size 0 0)
			(layers "F.Cu" "F.Mask" "F.Paste")
			(net "H_CPU1_MEMHOT_OUT_VT_N")
		)
	)
	(footprint ""
		(layer "F.Cu")
		(at 426.677836 -17.612614 90)
		(property "Reference" "C864"
			(at 0 0 90)
			(layer "F.SilkS")
			(hide yes)
			(effects
				(font
					(size 1.27 1.27)
				)
			)
		)
		(property "Value" ""
			(at 0 0 90)
			(layer "F.Fab")
			(effects
				(font
					(size 1.27 1.27)
				)
			)
		)
		(duplicate_pad_numbers_are_jumpers no)
		(fp_line
			(start 0.299974 -0.150114)
			(end 0.299974 0.150114)
			(stroke
				(width 0.1)
				(type default)
			)
			(layer "F.Fab")
		)
		(fp_line
			(start -0.299974 -0.150114)
			(end 0.299974 -0.150114)
			(stroke
				(width 0.1)
				(type default)
			)
			(layer "F.Fab")
		)
		(fp_line
			(start 0.299974 0.150114)
			(end -0.299974 0.150114)
			(stroke
				(width 0.1)
				(type default)
			)
			(layer "F.Fab")
		)
		(fp_line
			(start -0.299974 0.150114)
			(end -0.299974 -0.150114)
			(stroke
				(width 0.1)
				(type default)
			)
			(layer "F.Fab")
		)
		(pad "1" smd rect
			(at -0.2667 0 90)
			(size 0.3048 0.381)
			(layers "F.Cu" "F.Mask" "F.Paste")
			(net "P5E_CPU0_PE1_TX_C_DN<2>")
		)
		(pad "2" smd rect
			(at 0.2667 0 90)
			(size 0.3048 0.381)
			(layers "F.Cu" "F.Mask" "F.Paste")
			(net "P5E_CPU0_PE1_TX_DN<2>")
		)
	)
	(footprint ""
		(layer "F.Cu")
		(at 354.262944 -240.276888 90)
		(property "Reference" "C1031"
			(at 0 0 90)
			(layer "F.SilkS")
			(hide yes)
			(effects
				(font
					(size 1.27 1.27)
				)
			)
		)
		(property "Value" ""
			(at 0 0 90)
			(layer "F.Fab")
			(effects
				(font
					(size 1.27 1.27)
				)
			)
		)
		(duplicate_pad_numbers_are_jumpers no)
		(fp_line
			(start 0.7874 -0.4064)
			(end 0.7874 0.4064)
			(stroke
				(width 0.1524)
				(type default)
			)
			(layer "F.SilkS")
		)
		(fp_line
			(start -0.7874 -0.4064)
			(end 0.7874 -0.4064)
			(stroke
				(width 0.1524)
				(type default)
			)
			(layer "F.SilkS")
		)
		(fp_line
			(start 0.7874 0.4064)
			(end -0.7874 0.4064)
			(stroke
				(width 0.1524)
				(type default)
			)
			(layer "F.SilkS")
		)
		(fp_line
			(start -0.7874 0.4064)
			(end -0.7874 -0.4064)
			(stroke
				(width 0.1524)
				(type default)
			)
			(layer "F.SilkS")
		)
		(fp_line
			(start -0.12065 -0.305054)
			(end -0.12065 -0.2794)
			(stroke
				(width 0.1)
				(type default)
			)
			(layer "F.Fab")
		)
		(fp_line
			(start -0.67945 -0.305054)
			(end -0.12065 -0.305054)
			(stroke
				(width 0.1)
				(type default)
			)
			(layer "F.Fab")
		)
		(fp_line
			(start 0.67945 -0.3048)
			(end 0.67945 0.3048)
			(stroke
				(width 0.1)
				(type default)
			)
			(layer "F.Fab")
		)
		(fp_line
			(start 0.12065 -0.3048)
			(end 0.67945 -0.3048)
			(stroke
				(width 0.1)
				(type default)
			)
			(layer "F.Fab")
		)
		(fp_line
			(start 0.12065 -0.2794)
			(end 0.12065 -0.3048)
			(stroke
				(width 0.1)
				(type default)
			)
			(layer "F.Fab")
		)
		(fp_line
			(start -0.12065 -0.2794)
			(end 0.12065 -0.2794)
			(stroke
				(width 0.1)
				(type default)
			)
			(layer "F.Fab")
		)
		(fp_line
			(start 0.120396 0.2794)
			(end -0.12065 0.2794)
			(stroke
				(width 0.1)
				(type default)
			)
			(layer "F.Fab")
		)
		(fp_line
			(start -0.12065 0.2794)
			(end -0.12065 0.3048)
			(stroke
				(width 0.1)
				(type default)
			)
			(layer "F.Fab")
		)
		(fp_line
			(start 0.67945 0.3048)
			(end 0.120396 0.3048)
			(stroke
				(width 0.1)
				(type default)
			)
			(layer "F.Fab")
		)
		(fp_line
			(start 0.120396 0.3048)
			(end 0.120396 0.2794)
			(stroke
				(width 0.1)
				(type default)
			)
			(layer "F.Fab")
		)
		(fp_line
			(start -0.12065 0.3048)
			(end -0.67945 0.3048)
			(stroke
				(width 0.1)
				(type default)
			)
			(layer "F.Fab")
		)
		(fp_line
			(start -0.67945 0.3048)
			(end -0.67945 -0.305054)
			(stroke
				(width 0.1)
				(type default)
			)
			(layer "F.Fab")
		)
		(pad "1" smd circle
			(at -0.40005 0 90)
			(size 0 0)
			(layers "F.Cu" "F.Mask" "F.Paste")
			(net "PVCCIN_CPU0")
		)
		(pad "2" smd circle
			(at 0.40005 0 90)
			(size 0 0)
			(layers "F.Cu" "F.Mask" "F.Paste")
			(net "GND")
		)
	)
	(footprint ""
		(layer "F.Cu")
		(at 192.58788 -112.613948 90)
		(property "Reference" "R1100"
			(at 0 0 90)
			(layer "F.SilkS")
			(hide yes)
			(effects
				(font
					(size 1.27 1.27)
				)
			)
		)
		(property "Value" ""
			(at 0 0 90)
			(layer "F.Fab")
			(effects
				(font
					(size 1.27 1.27)
				)
			)
		)
		(duplicate_pad_numbers_are_jumpers no)
		(fp_line
			(start 0.7874 -0.4064)
			(end 0.7874 0.4064)
			(stroke
				(width 0.1524)
				(type default)
			)
			(layer "F.SilkS")
		)
		(fp_line
			(start -0.7874 -0.4064)
			(end 0.7874 -0.4064)
			(stroke
				(width 0.1524)
				(type default)
			)
			(layer "F.SilkS")
		)
		(fp_line
			(start 0.7874 0.4064)
			(end -0.7874 0.4064)
			(stroke
				(width 0.1524)
				(type default)
			)
			(layer "F.SilkS")
		)
		(fp_line
			(start -0.7874 0.4064)
			(end -0.7874 -0.4064)
			(stroke
				(width 0.1524)
				(type default)
			)
			(layer "F.SilkS")
		)
		(fp_line
			(start -0.12065 -0.305054)
			(end -0.12065 -0.2794)
			(stroke
				(width 0.1)
				(type default)
			)
			(layer "F.Fab")
		)
		(fp_line
			(start -0.67945 -0.305054)
			(end -0.12065 -0.305054)
			(stroke
				(width 0.1)
				(type default)
			)
			(layer "F.Fab")
		)
		(fp_line
			(start 0.67945 -0.3048)
			(end 0.67945 0.3048)
			(stroke
				(width 0.1)
				(type default)
			)
			(layer "F.Fab")
		)
		(fp_line
			(start 0.12065 -0.3048)
			(end 0.67945 -0.3048)
			(stroke
				(width 0.1)
				(type default)
			)
			(layer "F.Fab")
		)
		(fp_line
			(start 0.12065 -0.2794)
			(end 0.12065 -0.3048)
			(stroke
				(width 0.1)
				(type default)
			)
			(layer "F.Fab")
		)
		(fp_line
			(start -0.12065 -0.2794)
			(end 0.12065 -0.2794)
			(stroke
				(width 0.1)
				(type default)
			)
			(layer "F.Fab")
		)
		(fp_line
			(start 0.120396 0.2794)
			(end -0.12065 0.2794)
			(stroke
				(width 0.1)
				(type default)
			)
			(layer "F.Fab")
		)
		(fp_line
			(start -0.12065 0.2794)
			(end -0.12065 0.3048)
			(stroke
				(width 0.1)
				(type default)
			)
			(layer "F.Fab")
		)
		(fp_line
			(start 0.67945 0.3048)
			(end 0.120396 0.3048)
			(stroke
				(width 0.1)
				(type default)
			)
			(layer "F.Fab")
		)
		(fp_line
			(start 0.120396 0.3048)
			(end 0.120396 0.2794)
			(stroke
				(width 0.1)
				(type default)
			)
			(layer "F.Fab")
		)
		(fp_line
			(start -0.12065 0.3048)
			(end -0.67945 0.3048)
			(stroke
				(width 0.1)
				(type default)
			)
			(layer "F.Fab")
		)
		(fp_line
			(start -0.67945 0.3048)
			(end -0.67945 -0.305054)
			(stroke
				(width 0.1)
				(type default)
			)
			(layer "F.Fab")
		)
		(pad "1" smd circle
			(at -0.40005 0 90)
			(size 0 0)
			(layers "F.Cu" "F.Mask" "F.Paste")
			(net "CLK_25M_OSC_FPGA_R")
		)
		(pad "2" smd circle
			(at 0.40005 0 90)
			(size 0 0)
			(layers "F.Cu" "F.Mask" "F.Paste")
			(net "CLK_25M_OSC_MAIN_FPGA")
		)
	)
	(footprint ""
		(layer "F.Cu")
		(at 176.17948 -423.382948)
		(property "Reference" "R2924"
			(at 0 0 0)
			(layer "F.SilkS")
			(hide yes)
			(effects
				(font
					(size 1.27 1.27)
				)
			)
		)
		(property "Value" ""
			(at 0 0 0)
			(layer "F.Fab")
			(effects
				(font
					(size 1.27 1.27)
				)
			)
		)
		(duplicate_pad_numbers_are_jumpers no)
		(fp_line
			(start -0.7874 -0.4064)
			(end 0.7874 -0.4064)
			(stroke
				(width 0.1524)
				(type default)
			)
			(layer "F.SilkS")
		)
		(fp_line
			(start -0.7874 0.4064)
			(end -0.7874 -0.4064)
			(stroke
				(width 0.1524)
				(type default)
			)
			(layer "F.SilkS")
		)
		(fp_line
			(start 0.7874 -0.4064)
			(end 0.7874 0.4064)
			(stroke
				(width 0.1524)
				(type default)
			)
			(layer "F.SilkS")
		)
		(fp_line
			(start 0.7874 0.4064)
			(end -0.7874 0.4064)
			(stroke
				(width 0.1524)
				(type default)
			)
			(layer "F.SilkS")
		)
		(fp_line
			(start -0.67945 -0.305054)
			(end -0.12065 -0.305054)
			(stroke
				(width 0.1)
				(type default)
			)
			(layer "F.Fab")
		)
		(fp_line
			(start -0.67945 0.3048)
			(end -0.67945 -0.305054)
			(stroke
				(width 0.1)
				(type default)
			)
			(layer "F.Fab")
		)
		(fp_line
			(start -0.12065 -0.305054)
			(end -0.12065 -0.2794)
			(stroke
				(width 0.1)
				(type default)
			)
			(layer "F.Fab")
		)
		(fp_line
			(start -0.12065 -0.2794)
			(end 0.12065 -0.2794)
			(stroke
				(width 0.1)
				(type default)
			)
			(layer "F.Fab")
		)
		(fp_line
			(start -0.12065 0.2794)
			(end -0.12065 0.3048)
			(stroke
				(width 0.1)
				(type default)
			)
			(layer "F.Fab")
		)
		(fp_line
			(start -0.12065 0.3048)
			(end -0.67945 0.3048)
			(stroke
				(width 0.1)
				(type default)
			)
			(layer "F.Fab")
		)
		(fp_line
			(start 0.120396 0.2794)
			(end -0.12065 0.2794)
			(stroke
				(width 0.1)
				(type default)
			)
			(layer "F.Fab")
		)
		(fp_line
			(start 0.120396 0.3048)
			(end 0.120396 0.2794)
			(stroke
				(width 0.1)
				(type default)
			)
			(layer "F.Fab")
		)
		(fp_line
			(start 0.12065 -0.3048)
			(end 0.67945 -0.3048)
			(stroke
				(width 0.1)
				(type default)
			)
			(layer "F.Fab")
		)
		(fp_line
			(start 0.12065 -0.2794)
			(end 0.12065 -0.3048)
			(stroke
				(width 0.1)
				(type default)
			)
			(layer "F.Fab")
		)
		(fp_line
			(start 0.67945 -0.3048)
			(end 0.67945 0.3048)
			(stroke
				(width 0.1)
				(type default)
			)
			(layer "F.Fab")
		)
		(fp_line
			(start 0.67945 0.3048)
			(end 0.120396 0.3048)
			(stroke
				(width 0.1)
				(type default)
			)
			(layer "F.Fab")
		)
		(pad "1" smd circle
			(at -0.40005 0)
			(size 0 0)
			(layers "F.Cu" "F.Mask" "F.Paste")
			(net "RST_SWB_BIC_BUF_R_N")
		)
		(pad "2" smd circle
			(at 0.40005 0)
			(size 0 0)
			(layers "F.Cu" "F.Mask" "F.Paste")
			(net "RST_SWB_BIC_BUF_N")
		)
	)
)
